#ISCELL
  mstr_misc dns *
  *
#ISCELL
  mstr_symbols design_note *
  *
#ISCELL
  mstr_symbols intel_corp_bpage *
  *
#ISCELL
  mstr_standard offpage *
  page172_i10
#ISCELL
  mstr_standard offpage *
  page172_i11
#ISCELL
  mstr_standard offpage *
  page172_i12
#CELL
  mstr_conn conn7_e82125014 *
  page172_i17
#ISCELL
  mstr_symbols gnd *
  page172_i2
#CELL
  mstr_conn conn4_h73295001 *
  page172_i25
#ISCELL
  mstr_symbols gnd *
  page172_i26
#ISCELL
  mstr_symbols gnd *
  page172_i35
#CELL
  mstr_discrete cap *
  page172_i36
#ISCELL
  mstr_symbols p12v *
  page172_i37
#CELL
  mstr_discrete fuse *
  page172_i38
#CELL
  mstr_discrete cap *
  page172_i39
#ISCELL
  mstr_symbols gnd *
  page172_i40
#CELL
  mstr_discrete fuse *
  page172_i41
#ISCELL
  mstr_symbols p5v *
  page172_i42
#CELL
  dev_discrete cap_a *
  page172_i5
#ISCELL
  mstr_symbols gnd *
  page172_i51
#CELL
  mstr_conn conn7_e82125014 *
  page172_i52
#CELL
  mstr_conn conn4_h73295001 *
  page172_i53
#ISCELL
  mstr_symbols gnd *
  page172_i54
#CELL
  dev_discrete cap_a *
  page172_i6
#CELL
  dev_discrete cap_a *
  page172_i7
#CELL
  dev_discrete cap_a *
  page172_i8
#ISCELL
  mstr_standard offpage *
  page172_i9
